# S9S_MB_2U (Grand Teton) — schematic netlist excerpt (pin names and nets, part order shuffled) for the footprints in the layout excerpt that follows; sources: Cadence DE-HDL packaged netlist, KiCad conversion of 03242023_DA0F0TMBIJ0_F0T_Motherboard_J_brd_V01_OCP.brd

C1099  Q_CAP_DIFFBUS  DIFF BUS_0.22UF 6.3V 20% X6S  pkg C0201  page 181 : \1\ = P3E_PCH_M2_TX_DN<3> ; \2\ = P3E_PCH_M2_TX_C_DN<3>
R3064  Q_RES  0 5% EMPTY  pkg 0402LF  page 197 : A = PECI_CPU_GTL ; B = PECI_BMC_ME

(kicad_pcb
	(version 20260206)
	(generator "pcbnew")
	(generator_version "10.0")
	(general
		(thickness 1.6)
		(legacy_teardrops no)
	)
	(paper "A4")
	(title_block
		(title "03242023_DA0F0TMBIJ0_F0T_Motherboard_J_brd_V01_OCP.brd")
		(comment 1 "Grand Teton / footprints 1386-1387 of 6105")
	)
	(layers
		(0 "F.Cu" signal "TOP")
		(4 "In1.Cu" signal "GND")
		(6 "In2.Cu" signal "IN1")
		(8 "In3.Cu" signal "GND1")
		(10 "In4.Cu" signal "IN2")
		(12 "In5.Cu" signal "GND2")
		(14 "In6.Cu" signal "IN3")
		(16 "In7.Cu" signal "GND3")
		(18 "In8.Cu" signal "VCC")
		(20 "In9.Cu" signal "VCC1")
		(22 "In10.Cu" signal "GND4")
		(24 "In11.Cu" signal "IN4")
		(26 "In12.Cu" signal "GND5")
		(28 "In13.Cu" signal "IN5")
		(30 "In14.Cu" signal "GND6")
		(32 "In15.Cu" signal "IN6")
		(34 "In16.Cu" signal "GND7")
		(2 "B.Cu" signal "BOTTOM")
		(9 "F.Adhes" user "F.Adhesive")
		(11 "B.Adhes" user "B.Adhesive")
		(13 "F.Paste" user "Package Geometry/Pastemask Top")
		(15 "B.Paste" user "Package Geometry/Pastemask Bottom")
		(5 "F.SilkS" user "Ref Des/Silkscreen Top")
		(7 "B.SilkS" user "Ref Des/Silkscreen Bottom")
		(1 "F.Mask" user "Board Geometry/Soldermask Top")
		(3 "B.Mask" user "Board Geometry/Soldermask Bottom")
		(17 "Dwgs.User" user "User.Drawings")
		(19 "Cmts.User" user "User.Comments")
		(21 "Eco1.User" user "User.Eco1")
		(23 "Eco2.User" user "User.Eco2")
		(25 "Edge.Cuts" user "Board Geometry/Outline")
		(27 "Margin" user)
		(31 "F.CrtYd" user "Package Geometry/Place Bound Top")
		(29 "B.CrtYd" user "Package Geometry/Place Bound Bottom")
		(35 "F.Fab" user "Ref Des/Assembly Top")
		(33 "B.Fab" user "Ref Des/Assembly Bottom")
	)
	(footprint ""
		(layer "F.Cu")
		(at 180.528468 -44.091098 180)
		(property "Reference" "C1099"
			(at 0 0 180)
			(layer "F.SilkS")
			(hide yes)
			(effects
				(font
					(size 1.27 1.27)
				)
			)
		)
		(property "Value" ""
			(at 0 0 180)
			(layer "F.Fab")
			(effects
				(font
					(size 1.27 1.27)
				)
			)
		)
		(duplicate_pad_numbers_are_jumpers no)
		(fp_line
			(start 0.299974 0.150114)
			(end -0.299974 0.150114)
			(stroke
				(width 0.1)
				(type default)
			)
			(layer "F.Fab")
		)
		(fp_line
			(start 0.299974 -0.150114)
			(end 0.299974 0.150114)
			(stroke
				(width 0.1)
				(type default)
			)
			(layer "F.Fab")
		)
		(fp_line
			(start -0.299974 0.150114)
			(end -0.299974 -0.150114)
			(stroke
				(width 0.1)
				(type default)
			)
			(layer "F.Fab")
		)
		(fp_line
			(start -0.299974 -0.150114)
			(end 0.299974 -0.150114)
			(stroke
				(width 0.1)
				(type default)
			)
			(layer "F.Fab")
		)
		(pad "1" smd rect
			(at -0.2667 0 180)
			(size 0.3048 0.381)
			(layers "F.Cu" "F.Mask" "F.Paste")
			(net "P3E_PCH_M2_TX_DN<3>")
		)
		(pad "2" smd rect
			(at 0.2667 0 180)
			(size 0.3048 0.381)
			(layers "F.Cu" "F.Mask" "F.Paste")
			(net "P3E_PCH_M2_TX_C_DN<3>")
		)
		(zone
			(layer "In1.Cu")
			(hatch none 0.5)
			(connect_pads
				(clearance 0)
			)
			(min_thickness 0.25)
			(keepout
				(tracks not_allowed)
				(vias allowed)
				(pads allowed)
				(copperpour not_allowed)
				(footprints allowed)
			)
			(placement
				(enabled no)
				(sheetname "")
			)
			(fill
				(thermal_gap 0.5)
				(thermal_bridge_width 0.5)
				(island_removal_mode 0)
			)
			(polygon
				(pts
					(arc
						(start 180.388768 -44.332398)
						(mid 180.44265 -44.31008)
						(end 180.464968 -44.256198)
					)
					(arc
						(start 180.464968 -43.925998)
						(mid 180.44265 -43.872116)
						(end 180.388768 -43.849798)
					)
					(arc
						(start 180.134768 -43.849798)
						(mid 180.080886 -43.872116)
						(end 180.058568 -43.925998)
					)
					(arc
						(start 180.058568 -44.256198)
						(mid 180.080886 -44.31008)
						(end 180.134768 -44.332398)
					)
				)
			)
		)
		(zone
			(layer "In1.Cu")
			(hatch none 0.5)
			(connect_pads
				(clearance 0)
			)
			(min_thickness 0.25)
			(keepout
				(tracks not_allowed)
				(vias allowed)
				(pads allowed)
				(copperpour not_allowed)
				(footprints allowed)
			)
			(placement
				(enabled no)
				(sheetname "")
			)
			(fill
				(thermal_gap 0.5)
				(thermal_bridge_width 0.5)
				(island_removal_mode 0)
			)
			(polygon
				(pts
					(arc
						(start 180.922168 -44.332398)
						(mid 180.97605 -44.31008)
						(end 180.998368 -44.256198)
					)
					(arc
						(start 180.998368 -43.925998)
						(mid 180.97605 -43.872116)
						(end 180.922168 -43.849798)
					)
					(arc
						(start 180.668168 -43.849798)
						(mid 180.614286 -43.872116)
						(end 180.591968 -43.925998)
					)
					(arc
						(start 180.591968 -44.256198)
						(mid 180.614286 -44.31008)
						(end 180.668168 -44.332398)
					)
				)
			)
		)
	)
	(footprint ""
		(layer "F.Cu")
		(at 309.030624 -62.375542 90)
		(property "Reference" "R3064"
			(at 0 0 90)
			(layer "F.SilkS")
			(hide yes)
			(effects
				(font
					(size 1.27 1.27)
				)
			)
		)
		(property "Value" ""
			(at 0 0 90)
			(layer "F.Fab")
			(effects
				(font
					(size 1.27 1.27)
				)
			)
		)
		(duplicate_pad_numbers_are_jumpers no)
		(fp_line
			(start 0.7874 -0.4064)
			(end 0.7874 0.4064)
			(stroke
				(width 0.1524)
				(type default)
			)
			(layer "F.SilkS")
		)
		(fp_line
			(start -0.7874 -0.4064)
			(end 0.7874 -0.4064)
			(stroke
				(width 0.1524)
				(type default)
			)
			(layer "F.SilkS")
		)
		(fp_line
			(start 0.7874 0.4064)
			(end -0.7874 0.4064)
			(stroke
				(width 0.1524)
				(type default)
			)
			(layer "F.SilkS")
		)
		(fp_line
			(start -0.7874 0.4064)
			(end -0.7874 -0.4064)
			(stroke
				(width 0.1524)
				(type default)
			)
			(layer "F.SilkS")
		)
		(fp_line
			(start -0.12065 -0.305054)
			(end -0.12065 -0.2794)
			(stroke
				(width 0.1)
				(type default)
			)
			(layer "F.Fab")
		)
		(fp_line
			(start -0.67945 -0.305054)
			(end -0.12065 -0.305054)
			(stroke
				(width 0.1)
				(type default)
			)
			(layer "F.Fab")
		)
		(fp_line
			(start 0.67945 -0.3048)
			(end 0.67945 0.3048)
			(stroke
				(width 0.1)
				(type default)
			)
			(layer "F.Fab")
		)
		(fp_line
			(start 0.12065 -0.3048)
			(end 0.67945 -0.3048)
			(stroke
				(width 0.1)
				(type default)
			)
			(layer "F.Fab")
		)
		(fp_line
			(start 0.12065 -0.2794)
			(end 0.12065 -0.3048)
			(stroke
				(width 0.1)
				(type default)
			)
			(layer "F.Fab")
		)
		(fp_line
			(start -0.12065 -0.2794)
			(end 0.12065 -0.2794)
			(stroke
				(width 0.1)
				(type default)
			)
			(layer "F.Fab")
		)
		(fp_line
			(start 0.120396 0.2794)
			(end -0.12065 0.2794)
			(stroke
				(width 0.1)
				(type default)
			)
			(layer "F.Fab")
		)
		(fp_line
			(start -0.12065 0.2794)
			(end -0.12065 0.3048)
			(stroke
				(width 0.1)
				(type default)
			)
			(layer "F.Fab")
		)
		(fp_line
			(start 0.67945 0.3048)
			(end 0.120396 0.3048)
			(stroke
				(width 0.1)
				(type default)
			)
			(layer "F.Fab")
		)
		(fp_line
			(start 0.120396 0.3048)
			(end 0.120396 0.2794)
			(stroke
				(width 0.1)
				(type default)
			)
			(layer "F.Fab")
		)
		(fp_line
			(start -0.12065 0.3048)
			(end -0.67945 0.3048)
			(stroke
				(width 0.1)
				(type default)
			)
			(layer "F.Fab")
		)
		(fp_line
			(start -0.67945 0.3048)
			(end -0.67945 -0.305054)
			(stroke
				(width 0.1)
				(type default)
			)
			(layer "F.Fab")
		)
		(pad "1" smd circle
			(at -0.40005 0 90)
			(size 0 0)
			(layers "F.Cu" "F.Mask" "F.Paste")
			(net "PECI_CPU_GTL")
		)
		(pad "2" smd circle
			(at 0.40005 0 90)
			(size 0 0)
			(layers "F.Cu" "F.Mask" "F.Paste")
			(net "PECI_BMC_ME")
		)
	)
)
